(kicad_pcb
	(version 20241229)
	(generator "pcbnew")
	(generator_version "9.0")
	(general
		(thickness 1.711)
		(legacy_teardrops no)
	)
	(paper "A4")
	(title_block
		(title "Antmicro Baseboard for Jetson AGX Thor")
		(date "2026-02-18")
		(rev "1.1.0")
		(company "Antmicro Ltd")
		(comment 1 "www.antmicro.com")
		(comment 9 "footprints 14-17 of 1170")
	)
	(layers
		(0 "F.Cu" signal)
		(4 "In1.Cu" signal)
		(6 "In2.Cu" signal)
		(8 "In3.Cu" signal)
		(10 "In4.Cu" jumper)
		(12 "In5.Cu" signal)
		(14 "In6.Cu" signal)
		(16 "In7.Cu" signal)
		(18 "In8.Cu" signal)
		(2 "B.Cu" signal)
		(9 "F.Adhes" user "F.Adhesive")
		(11 "B.Adhes" user "B.Adhesive")
		(13 "F.Paste" user)
		(15 "B.Paste" user)
		(5 "F.SilkS" user "F.Silkscreen")
		(7 "B.SilkS" user "B.Silkscreen")
		(1 "F.Mask" user)
		(3 "B.Mask" user)
		(17 "Dwgs.User" user "User.Drawings")
		(19 "Cmts.User" user "User.Comments")
		(21 "Eco1.User" user "User.Eco1")
		(23 "Eco2.User" user "User.Eco2")
		(25 "Edge.Cuts" user)
		(27 "Margin" user)
		(31 "F.CrtYd" user "F.Courtyard")
		(29 "B.CrtYd" user "B.Courtyard")
		(35 "F.Fab" user)
		(33 "B.Fab" user)
	)
	(footprint "antmicro-footprints:VQFN-16-1EP_3x3mm_P0.5mm_EP1.68x1.68mm"
		(layer "F.Cu")
		(at 139.181999 107.9)
		(property "Reference" "U71"
			(at 0.918001 -1.9 0)
			(layer "F.SilkS")
			(effects
				(font
					(size 0.7 0.7)
					(thickness 0.15)
				)
				(justify left bottom)
			)
		)
		(property "Value" "PCAL6408A_VQFN"
			(at 0 2.95 0)
			(layer "F.Fab")
			(effects
				(font
					(size 0.7 0.7)
					(thickness 0.15)
				)
				(justify left bottom)
			)
		)
		(property "Datasheet" "https://eu.mouser.com/datasheet/2/302/PCAL6408A-3139197.pdf"
			(at 0 0 0)
			(layer "F.Fab")
			(hide yes)
			(effects
				(font
					(size 1.27 1.27)
					(thickness 0.15)
				)
			)
		)
		(property "Description" "I/O Expander, 8 bit, I2C, 1.65-5.5 V, HVQFN, 16 Pins"
			(at 0 0 0)
			(layer "F.Fab")
			(hide yes)
			(effects
				(font
					(size 1.27 1.27)
					(thickness 0.15)
				)
			)
		)
		(property "MPN" "PCAL6408ABSHP"
			(at 0 0 0)
			(unlocked yes)
			(layer "F.Fab")
			(hide yes)
			(effects
				(font
					(size 1 1)
					(thickness 0.15)
				)
			)
		)
		(property "Manufacturer" "NXP"
			(at 0 0 0)
			(unlocked yes)
			(layer "F.Fab")
			(hide yes)
			(effects
				(font
					(size 1 1)
					(thickness 0.15)
				)
			)
		)
		(property "Author" "Antmicro"
			(at 0 0 0)
			(unlocked yes)
			(layer "F.Fab")
			(hide yes)
			(effects
				(font
					(size 1 1)
					(thickness 0.15)
				)
			)
		)
		(property "License" "Apache-2.0"
			(at 0 0 0)
			(unlocked yes)
			(layer "F.Fab")
			(hide yes)
			(effects
				(font
					(size 1 1)
					(thickness 0.15)
				)
			)
		)
		(sheetname "/Peripherals/")
		(sheetfile "peripherals.kicad_sch")
		(attr smd)
		(fp_line
			(start -1.5 -1.2)
			(end -1.5 -1)
			(stroke
				(width 0.15)
				(type solid)
			)
			(layer "F.SilkS")
		)
		(fp_line
			(start -1.5 -1.2)
			(end -1.2 -1.5)
			(stroke
				(width 0.15)
				(type solid)
			)
			(layer "F.SilkS")
		)
		(fp_line
			(start -1.5 1.499)
			(end -1.5 1)
			(stroke
				(width 0.15)
				(type solid)
			)
			(layer "F.SilkS")
		)
		(fp_line
			(start -1.5 1.499)
			(end -1 1.5)
			(stroke
				(width 0.15)
				(type solid)
			)
			(layer "F.SilkS")
		)
		(fp_line
			(start -1 -1.501)
			(end -1.2 -1.5)
			(stroke
				(width 0.15)
				(type solid)
			)
			(layer "F.SilkS")
		)
		(fp_line
			(start 1 1.499)
			(end 1.499 1.499)
			(stroke
				(width 0.15)
				(type solid)
			)
			(layer "F.SilkS")
		)
		(fp_line
			(start 1.499 -1.5)
			(end 1 -1.5)
			(stroke
				(width 0.15)
				(type solid)
			)
			(layer "F.SilkS")
		)
		(fp_line
			(start 1.5 -1)
			(end 1.499 -1.5)
			(stroke
				(width 0.15)
				(type solid)
			)
			(layer "F.SilkS")
		)
		(fp_line
			(start 1.5 1)
			(end 1.499 1.499)
			(stroke
				(width 0.15)
				(type solid)
			)
			(layer "F.SilkS")
		)
		(fp_circle
			(center -1.6 -1.6)
			(end -1.55 -1.6)
			(stroke
				(width 0.15)
				(type solid)
			)
			(fill yes)
			(layer "F.SilkS")
		)
		(fp_rect
			(start -1.75 -1.75)
			(end 1.75 1.75)
			(stroke
				(width 0.05)
				(type solid)
			)
			(fill no)
			(layer "F.CrtYd")
		)
		(fp_line
			(start -1.5 -1.2)
			(end -1.5 1.499)
			(stroke
				(width 0.15)
				(type solid)
			)
			(layer "F.Fab")
		)
		(fp_line
			(start -1.5 -1.2)
			(end -1.2 -1.5)
			(stroke
				(width 0.15)
				(type solid)
			)
			(layer "F.Fab")
		)
		(fp_line
			(start -1.2 -1.5)
			(end 1.499 -1.5)
			(stroke
				(width 0.15)
				(type solid)
			)
			(layer "F.Fab")
		)
		(fp_line
			(start 1.499 1.499)
			(end -1.5 1.499)
			(stroke
				(width 0.15)
				(type solid)
			)
			(layer "F.Fab")
		)
		(fp_line
			(start 1.499 1.499)
			(end 1.499 -1.5)
			(stroke
				(width 0.15)
				(type solid)
			)
			(layer "F.Fab")
		)
		(fp_text user "License: Apache-2.0"
			(at -1.901 7.4 0)
			(layer "F.Fab")
			(effects
				(font
					(size 0.7 0.7)
					(thickness 0.15)
				)
				(justify left bottom)
			)
		)
		(fp_text user "${REFERENCE}"
			(at -1.901 4.998 0)
			(layer "F.Fab")
			(effects
				(font
					(size 0.7 0.7)
					(thickness 0.15)
				)
				(justify left bottom)
			)
		)
		(fp_text user "Author: Antmicro"
			(at -1.901 6.2 0)
			(layer "F.Fab")
			(effects
				(font
					(size 0.7 0.7)
					(thickness 0.15)
				)
				(justify left bottom)
			)
		)
		(pad "1" smd roundrect
			(at -1.4 -0.75)
			(size 0.6 0.25)
			(layers "F.Cu" "F.Mask" "F.Paste")
			(roundrect_rratio 0.2)
			(net 1310 "Net-(U71-~{RESET})")
			(pinfunction "~{RESET}")
			(pintype "input")
		)
		(pad "2" smd roundrect
			(at -1.4 -0.25)
			(size 0.6 0.25)
			(layers "F.Cu" "F.Mask" "F.Paste")
			(roundrect_rratio 0.2)
			(net 1315 "/Peripherals/GPIOEX_P0_0")
			(pinfunction "P0")
			(pintype "bidirectional")
		)
		(pad "3" smd roundrect
			(at -1.4 0.25)
			(size 0.6 0.25)
			(layers "F.Cu" "F.Mask" "F.Paste")
			(roundrect_rratio 0.2)
			(net 1314 "/Peripherals/GPIOEX_P0_1")
			(pinfunction "P1")
			(pintype "bidirectional")
		)
		(pad "4" smd roundrect
			(at -1.4 0.75)
			(size 0.6 0.25)
			(layers "F.Cu" "F.Mask" "F.Paste")
			(roundrect_rratio 0.2)
			(net 1313 "/Peripherals/GPIOEX_P0_2")
			(pinfunction "P2")
			(pintype "bidirectional")
		)
		(pad "5" smd roundrect
			(at -0.75 1.4 90)
			(size 0.6 0.25)
			(layers "F.Cu" "F.Mask" "F.Paste")
			(roundrect_rratio 0.2)
			(net 1312 "/Peripherals/GPIOEX_P0_3")
			(pinfunction "P3")
			(pintype "bidirectional")
		)
		(pad "6" smd roundrect
			(at -0.25 1.4 90)
			(size 0.6 0.25)
			(layers "F.Cu" "F.Mask" "F.Paste")
			(roundrect_rratio 0.2)
			(net 1 "GND")
			(pinfunction "V_{ss}")
			(pintype "power_in")
		)
		(pad "7" smd roundrect
			(at 0.25 1.4 90)
			(size 0.6 0.25)
			(layers "F.Cu" "F.Mask" "F.Paste")
			(roundrect_rratio 0.2)
			(net 1316 "/Peripherals/GPIOEX_P0_4")
			(pinfunction "P4")
			(pintype "bidirectional")
		)
		(pad "8" smd roundrect
			(at 0.75 1.4 90)
			(size 0.6 0.25)
			(layers "F.Cu" "F.Mask" "F.Paste")
			(roundrect_rratio 0.2)
			(net 1317 "/Peripherals/GPIOEX_P0_5")
			(pinfunction "P5")
			(pintype "bidirectional")
		)
		(pad "9" smd roundrect
			(at 1.4 0.75 180)
			(size 0.6 0.25)
			(layers "F.Cu" "F.Mask" "F.Paste")
			(roundrect_rratio 0.2)
			(net 1318 "/Peripherals/GPIOEX_P0_6")
			(pinfunction "P6")
			(pintype "bidirectional")
		)
		(pad "10" smd roundrect
			(at 1.4 0.25 180)
			(size 0.6 0.25)
			(layers "F.Cu" "F.Mask" "F.Paste")
			(roundrect_rratio 0.2)
			(net 1319 "/Peripherals/GPIOEX_P0_7")
			(pinfunction "P7")
			(pintype "bidirectional")
		)
		(pad "11" smd roundrect
			(at 1.4 -0.25 180)
			(size 0.6 0.25)
			(layers "F.Cu" "F.Mask" "F.Paste")
			(roundrect_rratio 0.2)
			(net 1309 "/Peripherals/GPIO_EXP_IRQ")
			(pinfunction "~{INT}")
			(pintype "output")
		)
		(pad "12" smd roundrect
			(at 1.4 -0.75 180)
			(size 0.6 0.25)
			(layers "F.Cu" "F.Mask" "F.Paste")
			(roundrect_rratio 0.2)
			(net 853 "/I2C_{SYS}.SCL")
			(pinfunction "SCL")
			(pintype "input")
		)
		(pad "13" smd roundrect
			(at 0.75 -1.4 270)
			(size 0.6 0.25)
			(layers "F.Cu" "F.Mask" "F.Paste")
			(roundrect_rratio 0.2)
			(net 850 "/I2C_{SYS}.SDA")
			(pinfunction "SDA")
			(pintype "bidirectional")
		)
		(pad "14" smd roundrect
			(at 0.25 -1.4 270)
			(size 0.6 0.25)
			(layers "F.Cu" "F.Mask" "F.Paste")
			(roundrect_rratio 0.2)
			(net 2 "+3V3")
			(pinfunction "VDD_{(P)}")
			(pintype "power_in")
		)
		(pad "15" smd roundrect
			(at -0.25 -1.4 270)
			(size 0.6 0.25)
			(layers "F.Cu" "F.Mask" "F.Paste")
			(roundrect_rratio 0.2)
			(net 2 "+3V3")
			(pinfunction "VDD_{(I2C)}")
			(pintype "power_in")
		)
		(pad "16" smd roundrect
			(at -0.75 -1.4 270)
			(size 0.6 0.25)
			(layers "F.Cu" "F.Mask" "F.Paste")
			(roundrect_rratio 0.2)
			(net 1311 "Net-(U71-ADDR)")
			(pinfunction "ADDR")
			(pintype "passive")
		)
		(pad "17" smd roundrect
			(at 0 0)
			(size 1.68 1.68)
			(layers "F.Cu" "F.Mask" "F.Paste")
			(roundrect_rratio 0.02976190476)
			(net 1324 "unconnected-(U71-EP-Pad17)")
			(pinfunction "EP")
			(pintype "power_in+no_connect")
		)
	)
	(footprint "antmicro-footprints:TP_SMD_0.75mm"
		(layer "F.Cu")
		(at 168.5 57.17 90)
		(property "Reference" "TP63"
			(at -2.15 -0.63 90)
			(layer "F.SilkS")
			(hide yes)
			(effects
				(font
					(size 0.7 0.7)
					(thickness 0.15)
				)
				(justify left bottom)
			)
		)
		(property "Value" "TP_0.75mm_SMD"
			(at 0 1.2 90)
			(layer "F.Fab")
			(effects
				(font
					(size 0.7 0.7)
					(thickness 0.15)
				)
				(justify left bottom)
			)
		)
		(property "Description" "SMT test point"
			(at 0 0 90)
			(layer "F.Fab")
			(hide yes)
			(effects
				(font
					(size 1.27 1.27)
					(thickness 0.15)
				)
			)
		)
		(property "MPN" ""
			(at 0 0 90)
			(unlocked yes)
			(layer "F.Fab")
			(hide yes)
			(effects
				(font
					(size 1 1)
					(thickness 0.15)
				)
			)
		)
		(property "Manufacturer" ""
			(at 0 0 90)
			(unlocked yes)
			(layer "F.Fab")
			(hide yes)
			(effects
				(font
					(size 1 1)
					(thickness 0.15)
				)
			)
		)
		(property "Author" "Antmicro"
			(at 0 0 90)
			(unlocked yes)
			(layer "F.Fab")
			(hide yes)
			(effects
				(font
					(size 1 1)
					(thickness 0.15)
				)
			)
		)
		(property "License" "Apache-2.0"
			(at 0 0 90)
			(unlocked yes)
			(layer "F.Fab")
			(hide yes)
			(effects
				(font
					(size 1 1)
					(thickness 0.15)
				)
			)
		)
		(sheetname "/Power/")
		(sheetfile "power.kicad_sch")
		(attr exclude_from_pos_files exclude_from_bom)
		(fp_circle
			(center 0 0)
			(end 0.475 0)
			(stroke
				(width 0.05)
				(type default)
			)
			(fill no)
			(layer "F.CrtYd")
		)
		(fp_text user "Author: Antmicro"
			(at -0.4 3.901 90)
			(layer "F.Fab")
			(effects
				(font
					(size 0.7 0.7)
					(thickness 0.15)
				)
				(justify left bottom)
			)
		)
		(fp_text user "${REFERENCE}"
			(at -0.4 2.7 90)
			(layer "F.Fab")
			(effects
				(font
					(size 0.7 0.7)
					(thickness 0.15)
				)
				(justify left bottom)
			)
		)
		(fp_text user "License: Apache-2.0"
			(at -0.4 5.101 90)
			(layer "F.Fab")
			(effects
				(font
					(size 0.7 0.7)
					(thickness 0.15)
				)
				(justify left bottom)
			)
		)
		(pad "1" smd circle
			(at 0 0 90)
			(size 0.75 0.75)
			(layers "F.Cu" "F.Mask")
			(net 4 "+3V3_AON")
			(pinfunction "1")
			(pintype "passive")
		)
	)
	(footprint "antmicro-footprints:C_0805_2012Metric"
		(layer "F.Cu")
		(at 162.2 93.3 -90)
		(descr "Capacitor SMD 0805")
		(tags "capacitor SMD 0805")
		(property "Reference" "C247"
			(at -4.7 0.3 90)
			(layer "F.SilkS")
			(effects
				(font
					(size 0.7 0.7)
					(thickness 0.15)
				)
				(justify right top)
			)
		)
		(property "Value" "C_22u_25V_0805"
			(at -2.055717 1.963152 90)
			(layer "F.Fab")
			(effects
				(font
					(size 0.7 0.7)
					(thickness 0.15)
				)
				(justify right top)
			)
		)
		(property "Datasheet" "https://product.samsungsem.com/mlcc/CL21A226MAYNNN.do"
			(at 0 0 90)
			(layer "F.Fab")
			(hide yes)
			(effects
				(font
					(size 1.27 1.27)
					(thickness 0.15)
				)
			)
		)
		(property "Description" "SMT Multilayer Ceramic Capacitor, 22uF, +/-20%, 25V, X5R, 0805 [2012 Metric]"
			(at 0 0 90)
			(layer "F.Fab")
			(hide yes)
			(effects
				(font
					(size 1.27 1.27)
					(thickness 0.15)
				)
			)
		)
		(property "MPN" "CL21A226MAYNNNE"
			(at 0 0 270)
			(unlocked yes)
			(layer "F.Fab")
			(hide yes)
			(effects
				(font
					(size 1 1)
					(thickness 0.15)
				)
			)
		)
		(property "Manufacturer" "Samsung Electro-Mechanics"
			(at 0 0 270)
			(unlocked yes)
			(layer "F.Fab")
			(hide yes)
			(effects
				(font
					(size 1 1)
					(thickness 0.15)
				)
			)
		)
		(property "License" "Apache-2.0"
			(at 0 0 270)
			(unlocked yes)
			(layer "F.Fab")
			(hide yes)
			(effects
				(font
					(size 1 1)
					(thickness 0.15)
				)
			)
		)
		(property "Author" "Antmicro"
			(at 0 0 270)
			(unlocked yes)
			(layer "F.Fab")
			(hide yes)
			(effects
				(font
					(size 1 1)
					(thickness 0.15)
				)
			)
		)
		(property "Val" "22u"
			(at 0 0 270)
			(unlocked yes)
			(layer "F.Fab")
			(hide yes)
			(effects
				(font
					(size 1 1)
					(thickness 0.15)
				)
			)
		)
		(property "Voltage" "25V"
			(at 0 0 270)
			(unlocked yes)
			(layer "F.Fab")
			(hide yes)
			(effects
				(font
					(size 1 1)
					(thickness 0.15)
				)
			)
		)
		(property "Dielectric" "X5R"
			(at 0 0 270)
			(unlocked yes)
			(layer "F.Fab")
			(hide yes)
			(effects
				(font
					(size 1 1)
					(thickness 0.15)
				)
			)
		)
		(property "Public" "False"
			(at 0 0 270)
			(unlocked yes)
			(layer "F.Fab")
			(hide yes)
			(effects
				(font
					(size 1 1)
					(thickness 0.15)
				)
			)
		)
		(component_classes
			(class "DCDC_SOM")
		)
		(sheetname "/DCDC/")
		(sheetfile "dcdc.kicad_sch")
		(attr smd)
		(fp_line
			(start -0.3 0.7)
			(end 0.3 0.7)
			(stroke
				(width 0.15)
				(type solid)
			)
			(layer "F.SilkS")
		)
		(fp_line
			(start -0.3 -0.7)
			(end 0.3 -0.7)
			(stroke
				(width 0.15)
				(type solid)
			)
			(layer "F.SilkS")
		)
		(fp_rect
			(start 1.95 -0.9)
			(end -1.95 0.9)
			(stroke
				(width 0.05)
				(type default)
			)
			(fill no)
			(layer "F.CrtYd")
		)
		(fp_rect
			(start -0.95 -0.675)
			(end 0.95 0.675)
			(stroke
				(width 0.15)
				(type solid)
			)
			(fill no)
			(layer "F.Fab")
		)
		(fp_text user "License: Apache-2.0"
			(at -1.9 4.947 90)
			(layer "F.Fab")
			(effects
				(font
					(size 0.7 0.7)
					(thickness 0.15)
				)
				(justify right top)
			)
		)
		(fp_text user "Author: Antmicro"
			(at -1.9 5.947 90)
			(layer "F.Fab")
			(effects
				(font
					(size 0.7 0.7)
					(thickness 0.15)
				)
				(justify right top)
			)
		)
		(fp_text user "${REFERENCE}"
			(at -1.9 3.947 90)
			(layer "F.Fab")
			(effects
				(font
					(size 0.7 0.7)
					(thickness 0.15)
				)
				(justify right top)
			)
		)
		(pad "1" smd roundrect
			(at -1.1 0 270)
			(size 1.2 1.3)
			(layers "F.Cu" "F.Mask" "F.Paste")
			(roundrect_rratio 0.25)
			(net 1 "GND")
			(pintype "passive")
		)
		(pad "2" smd roundrect
			(at 1.1 0 270)
			(size 1.2 1.3)
			(layers "F.Cu" "F.Mask" "F.Paste")
			(roundrect_rratio 0.25)
			(net 903 "/DCDC/16V_OUT")
			(pintype "passive")
		)
	)
	(footprint "antmicro-footprints:R_0402_1005Metric"
		(layer "F.Cu")
		(at 156.72 112.2 180)
		(descr "Resistor SMD 0402")
		(tags "resistor SMD 0402")
		(property "Reference" "R376"
			(at -3.68 0.4 0)
			(layer "F.SilkS")
			(effects
				(font
					(size 0.7 0.7)
					(thickness 0.15)
				)
				(justify right top)
			)
		)
		(property "Value" "R_2k2_0402"
			(at -1.011843 1.772047 0)
			(layer "F.Fab")
			(effects
				(font
					(size 0.7 0.7)
					(thickness 0.15)
				)
				(justify right top)
			)
		)
		(property "Datasheet" "https://www.bourns.com/docs/product-datasheets/cr.pdf"
			(at 0 0 0)
			(layer "F.Fab")
			(hide yes)
			(effects
				(font
					(size 1.27 1.27)
					(thickness 0.15)
				)
			)
		)
		(property "Description" "SMD Chip Resistor, 2.2 kohm, ± 1%, 62.5 mW, 0402 [1005 Metric], Thick Film, General Purpose"
			(at 0 0 0)
			(layer "F.Fab")
			(hide yes)
			(effects
				(font
					(size 1.27 1.27)
					(thickness 0.15)
				)
			)
		)
		(property "MPN" "CR0402-FX-2201GLF"
			(at 0 0 180)
			(unlocked yes)
			(layer "F.Fab")
			(hide yes)
			(effects
				(font
					(size 1 1)
					(thickness 0.15)
				)
			)
		)
		(property "Manufacturer" "Bourns"
			(at 0 0 180)
			(unlocked yes)
			(layer "F.Fab")
			(hide yes)
			(effects
				(font
					(size 1 1)
					(thickness 0.15)
				)
			)
		)
		(property "License" "Apache-2.0"
			(at 0 0 180)
			(unlocked yes)
			(layer "F.Fab")
			(hide yes)
			(effects
				(font
					(size 1 1)
					(thickness 0.15)
				)
			)
		)
		(property "Author" "Antmicro"
			(at 0 0 180)
			(unlocked yes)
			(layer "F.Fab")
			(hide yes)
			(effects
				(font
					(size 1 1)
					(thickness 0.15)
				)
			)
		)
		(property "Val" "2k2"
			(at 0 0 180)
			(unlocked yes)
			(layer "F.Fab")
			(hide yes)
			(effects
				(font
					(size 1 1)
					(thickness 0.15)
				)
			)
		)
		(property "Tolerance" "1%"
			(at 0 0 180)
			(unlocked yes)
			(layer "F.Fab")
			(hide yes)
			(effects
				(font
					(size 1 1)
					(thickness 0.15)
				)
			)
		)
		(sheetname "/SoM_IO/")
		(sheetfile "som_io.kicad_sch")
		(attr smd)
		(fp_rect
			(start -0.925 -0.47)
			(end 0.925 0.47)
			(stroke
				(width 0.05)
				(type default)
			)
			(fill no)
			(layer "F.CrtYd")
		)
		(fp_rect
			(start -0.5 -0.25)
			(end 0.5 0.25)
			(stroke
				(width 0.15)
				(type solid)
			)
			(fill no)
			(layer "F.Fab")
		)
		(fp_text user "Author: Antmicro"
			(at -0.95 4.169 0)
			(layer "F.Fab")
			(effects
				(font
					(size 0.7 0.7)
					(thickness 0.15)
				)
				(justify right top)
			)
		)
		(fp_text user "License: Apache-2.0"
			(at -0.95 5.169 0)
			(layer "F.Fab")
			(effects
				(font
					(size 0.7 0.7)
					(thickness 0.15)
				)
				(justify right top)
			)
		)
		(fp_text user "${REFERENCE}"
			(at -0.95 3.168 0)
			(layer "F.Fab")
			(effects
				(font
					(size 0.7 0.7)
					(thickness 0.15)
				)
				(justify right top)
			)
		)
		(pad "1" smd roundrect
			(at -0.48 0 180)
			(size 0.59 0.64)
			(layers "F.Cu" "F.Mask" "F.Paste")
			(roundrect_rratio 0.25)
			(net 2 "+3V3")
			(pintype "passive")
		)
		(pad "2" smd roundrect
			(at 0.48 0 180)
			(size 0.59 0.64)
			(layers "F.Cu" "F.Mask" "F.Paste")
			(roundrect_rratio 0.25)
			(net 850 "/I2C_{SYS}.SDA")
			(pintype "passive")
		)
	)
)
